# BASEBOARD_FAB2 (Tioga Pass) — schematic netlist excerpt (pin names and nets, part order shuffled) for the footprints in the layout excerpt that follows; sources: Cadence DE-HDL packaged netlist, KiCad conversion of Wiwynn_Tioga_Pass_MB.brd

C2P16  CAP_A  0.1UF 16V 10% X7R  pkg 0402V  page 188 : A = P12V_STBY ; B = GND
C8P28  CAP  47UF 4V 20% X6S  pkg 0805  page 76 : A = PVCCIN_CPU1 ; B = GND
C6W4  CAP_A  0.1UF 16V 10% X7R  pkg 0402V  page 247 : A = P3V3_STBY ; B = GND

(kicad_pcb
	(version 20260206)
	(generator "pcbnew")
	(generator_version "10.0")
	(general
		(thickness 1.6)
		(legacy_teardrops no)
	)
	(paper "A4")
	(title_block
		(title "Wiwynn_Tioga_Pass_MB.brd")
		(comment 1 "Tioga Pass / footprints 4601-4603 of 4770")
	)
	(layers
		(0 "F.Cu" signal "TOP")
		(4 "In1.Cu" signal "L2GND")
		(6 "In2.Cu" signal "L3")
		(8 "In3.Cu" signal "L4GND")
		(10 "In4.Cu" signal "L5")
		(12 "In5.Cu" signal "L6GND")
		(14 "In6.Cu" signal "L7VCC")
		(16 "In7.Cu" signal "L8VCC")
		(18 "In8.Cu" signal "L9GND")
		(20 "In9.Cu" signal "L10")
		(22 "In10.Cu" signal "L11GND")
		(24 "In11.Cu" signal "L12")
		(26 "In12.Cu" signal "L13GND")
		(2 "B.Cu" signal "BOTTOM")
		(9 "F.Adhes" user "F.Adhesive")
		(11 "B.Adhes" user "B.Adhesive")
		(13 "F.Paste" user "Package Geometry/Pastemask Top")
		(15 "B.Paste" user "Package Geometry/Pastemask Bottom")
		(5 "F.SilkS" user "Ref Des/Silkscreen Top")
		(7 "B.SilkS" user "Ref Des/Silkscreen Bottom")
		(1 "F.Mask" user "Board Geometry/Soldermask Top")
		(3 "B.Mask" user "Board Geometry/Soldermask Bottom")
		(17 "Dwgs.User" user "User.Drawings")
		(19 "Cmts.User" user "User.Comments")
		(21 "Eco1.User" user "User.Eco1")
		(23 "Eco2.User" user "User.Eco2")
		(25 "Edge.Cuts" user "Board Geometry/Outline")
		(27 "Margin" user)
		(31 "F.CrtYd" user "Package Geometry/Place Bound Top")
		(29 "B.CrtYd" user "Package Geometry/Place Bound Bottom")
		(35 "F.Fab" user "Ref Des/Assembly Top")
		(33 "B.Fab" user "Ref Des/Assembly Bottom")
	)
	(footprint ""
		(layer "B.Cu")
		(at 443.0522 -64.7446 180)
		(property "Reference" "C2P16"
			(at 0 0 0)
			(layer "B.SilkS")
			(hide yes)
			(effects
				(font
					(size 1.27 1.27)
				)
				(justify mirror)
			)
		)
		(property "Value" ""
			(at 0 0 0)
			(layer "B.Fab")
			(effects
				(font
					(size 1.27 1.27)
				)
				(justify mirror)
			)
		)
		(duplicate_pad_numbers_are_jumpers no)
		(fp_poly
			(pts
				(xy -0.3048 -0.1016) (xy -0.3048 0.9906) (xy 0.3048 0.9906) (xy 0.3048 -0.1016)
			)
			(stroke
				(width 0)
				(type default)
			)
			(fill no)
			(layer "B.CrtYd")
		)
		(fp_line
			(start 0.3048 0.9906)
			(end -0.3048 0.9906)
			(stroke
				(width 0.1)
				(type default)
			)
			(layer "B.Fab")
		)
		(fp_line
			(start 0.3048 -0.1016)
			(end 0.3048 0.9906)
			(stroke
				(width 0.1)
				(type default)
			)
			(layer "B.Fab")
		)
		(fp_line
			(start -0.3048 0.9906)
			(end -0.3048 -0.1016)
			(stroke
				(width 0.1)
				(type default)
			)
			(layer "B.Fab")
		)
		(fp_line
			(start -0.3048 -0.1016)
			(end 0.3048 -0.1016)
			(stroke
				(width 0.1)
				(type default)
			)
			(layer "B.Fab")
		)
		(pad "1" smd rect
			(at 0 0)
			(size 0.508 0.508)
			(layers "B.Cu" "B.Mask" "B.Paste")
			(net "P12V_STBY")
		)
		(pad "2" smd rect
			(at 0 0.889)
			(size 0.508 0.508)
			(layers "B.Cu" "B.Mask" "B.Paste")
			(net "GND")
		)
		(zone
			(layer "B.Cu")
			(hatch none 0.5)
			(connect_pads
				(clearance 0)
			)
			(min_thickness 0.25)
			(keepout
				(tracks not_allowed)
				(vias allowed)
				(pads allowed)
				(copperpour not_allowed)
				(footprints allowed)
			)
			(placement
				(enabled no)
				(sheetname "")
			)
			(fill
				(thermal_gap 0.5)
				(thermal_bridge_width 0.5)
				(island_removal_mode 0)
			)
			(polygon
				(pts
					(xy 442.7982 -65.3796) (xy 443.3062 -65.3796) (xy 443.3062 -64.9986) (xy 442.7982 -64.9986)
				)
			)
		)
		(zone
			(layer "B.Cu")
			(hatch none 0.5)
			(connect_pads
				(clearance 0)
			)
			(min_thickness 0.25)
			(keepout
				(tracks allowed)
				(vias not_allowed)
				(pads allowed)
				(copperpour not_allowed)
				(footprints allowed)
			)
			(placement
				(enabled no)
				(sheetname "")
			)
			(fill
				(thermal_gap 0.5)
				(thermal_bridge_width 0.5)
				(island_removal_mode 0)
			)
			(polygon
				(pts
					(xy 442.7982 -64.9986) (xy 443.3062 -64.9986) (xy 443.3062 -65.3796) (xy 442.7982 -65.3796)
				)
			)
		)
	)
	(footprint ""
		(layer "B.Cu")
		(at 397.764 -75.1967 -90)
		(property "Reference" "C6W4"
			(at 0.8382 -0.67818 270)
			(unlocked yes)
			(layer "B.SilkS")
			(effects
				(font
					(size 0.4064 0.254)
					(thickness 0.1524)
				)
				(justify left mirror)
			)
		)
		(property "Value" ""
			(at 0 0 90)
			(layer "B.Fab")
			(effects
				(font
					(size 1.27 1.27)
				)
				(justify mirror)
			)
		)
		(duplicate_pad_numbers_are_jumpers no)
		(fp_poly
			(pts
				(xy -0.3048 -0.1016) (xy -0.3048 0.9906) (xy 0.3048 0.9906) (xy 0.3048 -0.1016)
			)
			(stroke
				(width 0)
				(type default)
			)
			(fill no)
			(layer "B.CrtYd")
		)
		(fp_line
			(start -0.3048 0.9906)
			(end -0.3048 -0.1016)
			(stroke
				(width 0.1)
				(type default)
			)
			(layer "B.Fab")
		)
		(fp_line
			(start 0.3048 0.9906)
			(end -0.3048 0.9906)
			(stroke
				(width 0.1)
				(type default)
			)
			(layer "B.Fab")
		)
		(fp_line
			(start -0.3048 -0.1016)
			(end 0.3048 -0.1016)
			(stroke
				(width 0.1)
				(type default)
			)
			(layer "B.Fab")
		)
		(fp_line
			(start 0.3048 -0.1016)
			(end 0.3048 0.9906)
			(stroke
				(width 0.1)
				(type default)
			)
			(layer "B.Fab")
		)
		(pad "1" smd rect
			(at 0 0 90)
			(size 0.508 0.508)
			(layers "B.Cu" "B.Mask" "B.Paste")
			(net "P3V3_STBY")
		)
		(pad "2" smd rect
			(at 0 0.889 90)
			(size 0.508 0.508)
			(layers "B.Cu" "B.Mask" "B.Paste")
			(net "GND")
		)
		(zone
			(layer "B.Cu")
			(hatch none 0.5)
			(connect_pads
				(clearance 0)
			)
			(min_thickness 0.25)
			(keepout
				(tracks not_allowed)
				(vias allowed)
				(pads allowed)
				(copperpour not_allowed)
				(footprints allowed)
			)
			(placement
				(enabled no)
				(sheetname "")
			)
			(fill
				(thermal_gap 0.5)
				(thermal_bridge_width 0.5)
				(island_removal_mode 0)
			)
			(polygon
				(pts
					(xy 397.129 -74.9427) (xy 397.129 -75.4507) (xy 397.51 -75.4507) (xy 397.51 -74.9427)
				)
			)
		)
		(zone
			(layer "B.Cu")
			(hatch none 0.5)
			(connect_pads
				(clearance 0)
			)
			(min_thickness 0.25)
			(keepout
				(tracks allowed)
				(vias not_allowed)
				(pads allowed)
				(copperpour not_allowed)
				(footprints allowed)
			)
			(placement
				(enabled no)
				(sheetname "")
			)
			(fill
				(thermal_gap 0.5)
				(thermal_bridge_width 0.5)
				(island_removal_mode 0)
			)
			(polygon
				(pts
					(xy 397.51 -74.9427) (xy 397.51 -75.4507) (xy 397.129 -75.4507) (xy 397.129 -74.9427)
				)
			)
		)
	)
	(footprint ""
		(layer "B.Cu")
		(at 95.377254 -73.51014)
		(property "Reference" "C8P28"
			(at 0 0 0)
			(layer "B.SilkS")
			(hide yes)
			(effects
				(font
					(size 1.27 1.27)
				)
				(justify mirror)
			)
		)
		(property "Value" ""
			(at 0 0 0)
			(layer "B.Fab")
			(effects
				(font
					(size 1.27 1.27)
				)
				(justify mirror)
			)
		)
		(duplicate_pad_numbers_are_jumpers no)
		(fp_poly
			(pts
				(xy 0.7239 -0.2159) (xy -0.7239 -0.2159) (xy -0.7239 1.9939) (xy 0.7239 1.9939)
			)
			(stroke
				(width 0)
				(type default)
			)
			(fill no)
			(layer "B.CrtYd")
		)
		(fp_line
			(start -0.7239 -0.2159)
			(end 0.7239 -0.2159)
			(stroke
				(width 0.1)
				(type default)
			)
			(layer "B.Fab")
		)
		(fp_line
			(start -0.7239 1.9939)
			(end -0.7239 -0.2159)
			(stroke
				(width 0.1)
				(type default)
			)
			(layer "B.Fab")
		)
		(fp_line
			(start 0.7239 -0.2159)
			(end 0.7239 1.9939)
			(stroke
				(width 0.1)
				(type default)
			)
			(layer "B.Fab")
		)
		(fp_line
			(start 0.7239 1.9939)
			(end -0.7239 1.9939)
			(stroke
				(width 0.1)
				(type default)
			)
			(layer "B.Fab")
		)
		(pad "1" smd rect
			(at 0 0 180)
			(size 1.27 1.016)
			(layers "B.Cu" "B.Mask" "B.Paste")
			(net "PVCCIN_CPU1")
		)
		(pad "2" smd rect
			(at 0 1.778 180)
			(size 1.27 1.016)
			(layers "B.Cu" "B.Mask" "B.Paste")
			(net "GND")
		)
		(zone
			(layer "B.Cu")
			(hatch none 0.5)
			(connect_pads
				(clearance 0)
			)
			(min_thickness 0.25)
			(keepout
				(tracks not_allowed)
				(vias allowed)
				(pads allowed)
				(copperpour not_allowed)
				(footprints allowed)
			)
			(placement
				(enabled no)
				(sheetname "")
			)
			(fill
				(thermal_gap 0.5)
				(thermal_bridge_width 0.5)
				(island_removal_mode 0)
			)
			(polygon
				(pts
					(xy 96.012254 -73.00214) (xy 94.742254 -73.00214) (xy 94.742254 -72.24014) (xy 96.012254 -72.24014)
				)
			)
		)
	)
)
